(kicad_pcb
	(version 20260206)
	(generator "pcbnew")
	(generator_version "10.0")
	(general
		(thickness 1.6)
		(legacy_teardrops no)
	)
	(paper "A4")
	(title_block
		(title "01162023_DA0F0TEBIF0_F0T_Expander_BD_F_brd_V02_OCP.brd")
		(comment 1 "Grand Teton / footprints 3579-3586 of 9728")
	)
	(layers
		(0 "F.Cu" signal "TOP")
		(4 "In1.Cu" signal "GND")
		(6 "In2.Cu" signal "VCC")
		(8 "In3.Cu" signal "VCC1")
		(10 "In4.Cu" signal "GND1")
		(12 "In5.Cu" signal "IN1")
		(14 "In6.Cu" signal "GND2")
		(16 "In7.Cu" signal "IN2")
		(18 "In8.Cu" signal "GND3")
		(20 "In9.Cu" signal "IN3")
		(22 "In10.Cu" signal "GND4")
		(24 "In11.Cu" signal "IN4")
		(26 "In12.Cu" signal "GND5")
		(28 "In13.Cu" signal "IN5")
		(30 "In14.Cu" signal "GND6")
		(32 "In15.Cu" signal "IN6")
		(34 "In16.Cu" signal "GND7")
		(2 "B.Cu" signal "BOTTOM")
		(9 "F.Adhes" user "F.Adhesive")
		(11 "B.Adhes" user "B.Adhesive")
		(13 "F.Paste" user "Package Geometry/Pastemask Top")
		(15 "B.Paste" user "Package Geometry/Pastemask Bottom")
		(5 "F.SilkS" user "Ref Des/Silkscreen Top")
		(7 "B.SilkS" user "Ref Des/Silkscreen Bottom")
		(1 "F.Mask" user "Board Geometry/Soldermask Top")
		(3 "B.Mask" user "Board Geometry/Soldermask Bottom")
		(17 "Dwgs.User" user "User.Drawings")
		(19 "Cmts.User" user "User.Comments")
		(21 "Eco1.User" user "User.Eco1")
		(23 "Eco2.User" user "User.Eco2")
		(25 "Edge.Cuts" user "Board Geometry/Outline")
		(27 "Margin" user)
		(31 "F.CrtYd" user "Package Geometry/Place Bound Top")
		(29 "B.CrtYd" user "Package Geometry/Place Bound Bottom")
		(35 "F.Fab" user "Ref Des/Assembly Top")
		(33 "B.Fab" user "Ref Des/Assembly Bottom")
	)
	(footprint ""
		(layer "F.Cu")
		(at 2.796794 -18.037048 90)
		(property "Reference" "U398"
			(at -1.831848 2.335276 90)
			(unlocked yes)
			(layer "F.SilkS")
			(effects
				(font
					(size 0.7874 0.5842)
					(thickness 0.1524)
				)
			)
		)
		(property "Value" ""
			(at 0 0 90)
			(layer "F.Fab")
			(effects
				(font
					(size 1.27 1.27)
				)
			)
		)
		(duplicate_pad_numbers_are_jumpers no)
		(fp_line
			(start -1.949958 -1.610106)
			(end 1.949958 -1.610106)
			(stroke
				(width 0.1524)
				(type default)
			)
			(layer "F.SilkS")
		)
		(fp_line
			(start 1.949958 -1.560068)
			(end 1.949958 1.610106)
			(stroke
				(width 0.1524)
				(type default)
			)
			(layer "F.SilkS")
		)
		(fp_line
			(start 1.949958 1.610106)
			(end -1.949958 1.610106)
			(stroke
				(width 0.1524)
				(type default)
			)
			(layer "F.SilkS")
		)
		(fp_line
			(start -1.949958 1.610106)
			(end -1.949958 -1.610106)
			(stroke
				(width 0.1524)
				(type default)
			)
			(layer "F.SilkS")
		)
		(fp_line
			(start 0.750062 -1.560068)
			(end 0.750062 1.560068)
			(stroke
				(width 0.1)
				(type default)
			)
			(layer "F.Fab")
		)
		(fp_line
			(start -0.750062 -1.560068)
			(end 0.750062 -1.560068)
			(stroke
				(width 0.1)
				(type default)
			)
			(layer "F.Fab")
		)
		(fp_line
			(start 0.750062 1.560068)
			(end -0.750062 1.560068)
			(stroke
				(width 0.1)
				(type default)
			)
			(layer "F.Fab")
		)
		(fp_line
			(start -0.750062 1.560068)
			(end -0.750062 -1.560068)
			(stroke
				(width 0.1)
				(type default)
			)
			(layer "F.Fab")
		)
		(pad "D" smd rect
			(at 1.100074 0)
			(size 1.016 1.4224)
			(layers "F.Cu" "F.Mask" "F.Paste")
			(net "SSD0_LED_ISO_N")
		)
		(pad "G" smd rect
			(at -1.100074 -0.94996)
			(size 1.016 1.4224)
			(layers "F.Cu" "F.Mask" "F.Paste")
			(net "SSD0_LED_R")
		)
		(pad "S" smd rect
			(at -1.100074 0.94996)
			(size 1.016 1.4224)
			(layers "F.Cu" "F.Mask" "F.Paste")
			(net "GND")
		)
	)
	(footprint ""
		(layer "F.Cu")
		(at 101.562662 -100.406708 -90)
		(property "Reference" "PC307"
			(at 0 0 270)
			(layer "F.SilkS")
			(hide yes)
			(effects
				(font
					(size 1.27 1.27)
				)
			)
		)
		(property "Value" ""
			(at 0 0 270)
			(layer "F.Fab")
			(effects
				(font
					(size 1.27 1.27)
				)
			)
		)
		(duplicate_pad_numbers_are_jumpers no)
		(fp_line
			(start -1.524 0.762)
			(end -1.524 -0.762)
			(stroke
				(width 0.1524)
				(type default)
			)
			(layer "F.SilkS")
		)
		(fp_line
			(start 1.524 0.762)
			(end -1.524 0.762)
			(stroke
				(width 0.1524)
				(type default)
			)
			(layer "F.SilkS")
		)
		(fp_line
			(start -1.524 -0.762)
			(end 1.524 -0.762)
			(stroke
				(width 0.1524)
				(type default)
			)
			(layer "F.SilkS")
		)
		(fp_line
			(start 1.524 -0.762)
			(end 1.524 0.762)
			(stroke
				(width 0.1524)
				(type default)
			)
			(layer "F.SilkS")
		)
		(fp_line
			(start -1.1049 0.724916)
			(end 1.1049 0.724916)
			(stroke
				(width 0.1)
				(type default)
			)
			(layer "F.Fab")
		)
		(fp_line
			(start 1.1049 0.724916)
			(end 1.1049 -0.724916)
			(stroke
				(width 0.1)
				(type default)
			)
			(layer "F.Fab")
		)
		(fp_line
			(start -1.1049 -0.724916)
			(end -1.1049 0.724916)
			(stroke
				(width 0.1)
				(type default)
			)
			(layer "F.Fab")
		)
		(fp_line
			(start 1.1049 -0.724916)
			(end -1.1049 -0.724916)
			(stroke
				(width 0.1)
				(type default)
			)
			(layer "F.Fab")
		)
		(pad "1" smd rect
			(at -0.889 0 90)
			(size 1.016 1.27)
			(layers "F.Cu" "F.Mask" "F.Paste")
			(net "GND")
		)
		(pad "2" smd rect
			(at 0.889 0 90)
			(size 1.016 1.27)
			(layers "F.Cu" "F.Mask" "F.Paste")
			(net "P12V_AUX")
		)
	)
	(footprint ""
		(layer "F.Cu")
		(at 135.32358 -152.71115 90)
		(property "Reference" "R708"
			(at 0 0 90)
			(layer "F.SilkS")
			(hide yes)
			(effects
				(font
					(size 1.27 1.27)
				)
			)
		)
		(property "Value" ""
			(at 0 0 90)
			(layer "F.Fab")
			(effects
				(font
					(size 1.27 1.27)
				)
			)
		)
		(duplicate_pad_numbers_are_jumpers no)
		(fp_line
			(start 0.7874 -0.4064)
			(end 0.7874 0.4064)
			(stroke
				(width 0.1524)
				(type default)
			)
			(layer "F.SilkS")
		)
		(fp_line
			(start -0.7874 -0.4064)
			(end 0.7874 -0.4064)
			(stroke
				(width 0.1524)
				(type default)
			)
			(layer "F.SilkS")
		)
		(fp_line
			(start 0.7874 0.4064)
			(end -0.7874 0.4064)
			(stroke
				(width 0.1524)
				(type default)
			)
			(layer "F.SilkS")
		)
		(fp_line
			(start -0.7874 0.4064)
			(end -0.7874 -0.4064)
			(stroke
				(width 0.1524)
				(type default)
			)
			(layer "F.SilkS")
		)
		(fp_line
			(start -0.12065 -0.305054)
			(end -0.12065 -0.2794)
			(stroke
				(width 0.1)
				(type default)
			)
			(layer "F.Fab")
		)
		(fp_line
			(start -0.67945 -0.305054)
			(end -0.12065 -0.305054)
			(stroke
				(width 0.1)
				(type default)
			)
			(layer "F.Fab")
		)
		(fp_line
			(start 0.67945 -0.3048)
			(end 0.67945 0.3048)
			(stroke
				(width 0.1)
				(type default)
			)
			(layer "F.Fab")
		)
		(fp_line
			(start 0.12065 -0.3048)
			(end 0.67945 -0.3048)
			(stroke
				(width 0.1)
				(type default)
			)
			(layer "F.Fab")
		)
		(fp_line
			(start 0.12065 -0.2794)
			(end 0.12065 -0.3048)
			(stroke
				(width 0.1)
				(type default)
			)
			(layer "F.Fab")
		)
		(fp_line
			(start -0.12065 -0.2794)
			(end 0.12065 -0.2794)
			(stroke
				(width 0.1)
				(type default)
			)
			(layer "F.Fab")
		)
		(fp_line
			(start 0.120396 0.2794)
			(end -0.12065 0.2794)
			(stroke
				(width 0.1)
				(type default)
			)
			(layer "F.Fab")
		)
		(fp_line
			(start -0.12065 0.2794)
			(end -0.12065 0.3048)
			(stroke
				(width 0.1)
				(type default)
			)
			(layer "F.Fab")
		)
		(fp_line
			(start 0.67945 0.3048)
			(end 0.120396 0.3048)
			(stroke
				(width 0.1)
				(type default)
			)
			(layer "F.Fab")
		)
		(fp_line
			(start 0.120396 0.3048)
			(end 0.120396 0.2794)
			(stroke
				(width 0.1)
				(type default)
			)
			(layer "F.Fab")
		)
		(fp_line
			(start -0.12065 0.3048)
			(end -0.67945 0.3048)
			(stroke
				(width 0.1)
				(type default)
			)
			(layer "F.Fab")
		)
		(fp_line
			(start -0.67945 0.3048)
			(end -0.67945 -0.305054)
			(stroke
				(width 0.1)
				(type default)
			)
			(layer "F.Fab")
		)
		(pad "1" smd circle
			(at -0.40005 0 90)
			(size 0 0)
			(layers "F.Cu" "F.Mask" "F.Paste")
			(net "NIC2_ADC_A0")
		)
		(pad "2" smd circle
			(at 0.40005 0 90)
			(size 0 0)
			(layers "F.Cu" "F.Mask" "F.Paste")
			(net "GND")
		)
	)
	(footprint ""
		(layer "F.Cu")
		(at 338.074 -178.943 180)
		(property "Reference" "R4753"
			(at 0 0 180)
			(layer "F.SilkS")
			(hide yes)
			(effects
				(font
					(size 1.27 1.27)
				)
			)
		)
		(property "Value" ""
			(at 0 0 180)
			(layer "F.Fab")
			(effects
				(font
					(size 1.27 1.27)
				)
			)
		)
		(duplicate_pad_numbers_are_jumpers no)
		(fp_line
			(start 0.7874 0.4064)
			(end -0.7874 0.4064)
			(stroke
				(width 0.1524)
				(type default)
			)
			(layer "F.SilkS")
		)
		(fp_line
			(start 0.7874 -0.4064)
			(end 0.7874 0.4064)
			(stroke
				(width 0.1524)
				(type default)
			)
			(layer "F.SilkS")
		)
		(fp_line
			(start -0.7874 0.4064)
			(end -0.7874 -0.4064)
			(stroke
				(width 0.1524)
				(type default)
			)
			(layer "F.SilkS")
		)
		(fp_line
			(start -0.7874 -0.4064)
			(end 0.7874 -0.4064)
			(stroke
				(width 0.1524)
				(type default)
			)
			(layer "F.SilkS")
		)
		(fp_line
			(start 0.67945 0.3048)
			(end 0.120396 0.3048)
			(stroke
				(width 0.1)
				(type default)
			)
			(layer "F.Fab")
		)
		(fp_line
			(start 0.67945 -0.3048)
			(end 0.67945 0.3048)
			(stroke
				(width 0.1)
				(type default)
			)
			(layer "F.Fab")
		)
		(fp_line
			(start 0.12065 -0.2794)
			(end 0.12065 -0.3048)
			(stroke
				(width 0.1)
				(type default)
			)
			(layer "F.Fab")
		)
		(fp_line
			(start 0.12065 -0.3048)
			(end 0.67945 -0.3048)
			(stroke
				(width 0.1)
				(type default)
			)
			(layer "F.Fab")
		)
		(fp_line
			(start 0.120396 0.3048)
			(end 0.120396 0.2794)
			(stroke
				(width 0.1)
				(type default)
			)
			(layer "F.Fab")
		)
		(fp_line
			(start 0.120396 0.2794)
			(end -0.12065 0.2794)
			(stroke
				(width 0.1)
				(type default)
			)
			(layer "F.Fab")
		)
		(fp_line
			(start -0.12065 0.3048)
			(end -0.67945 0.3048)
			(stroke
				(width 0.1)
				(type default)
			)
			(layer "F.Fab")
		)
		(fp_line
			(start -0.12065 0.2794)
			(end -0.12065 0.3048)
			(stroke
				(width 0.1)
				(type default)
			)
			(layer "F.Fab")
		)
		(fp_line
			(start -0.12065 -0.2794)
			(end 0.12065 -0.2794)
			(stroke
				(width 0.1)
				(type default)
			)
			(layer "F.Fab")
		)
		(fp_line
			(start -0.12065 -0.305054)
			(end -0.12065 -0.2794)
			(stroke
				(width 0.1)
				(type default)
			)
			(layer "F.Fab")
		)
		(fp_line
			(start -0.67945 0.3048)
			(end -0.67945 -0.305054)
			(stroke
				(width 0.1)
				(type default)
			)
			(layer "F.Fab")
		)
		(fp_line
			(start -0.67945 -0.305054)
			(end -0.12065 -0.305054)
			(stroke
				(width 0.1)
				(type default)
			)
			(layer "F.Fab")
		)
		(pad "1" smd circle
			(at -0.40005 0 180)
			(size 0 0)
			(layers "F.Cu" "F.Mask" "F.Paste")
			(net "PRSNT_SSD9_FPGA_PCA9555_N")
		)
		(pad "2" smd circle
			(at 0.40005 0 180)
			(size 0 0)
			(layers "F.Cu" "F.Mask" "F.Paste")
			(net "PRSNT_SSD9_FPGA_R_N")
		)
	)
	(footprint ""
		(layer "F.Cu")
		(at 425.728892 -356.244906 90)
		(property "Reference" "C2456"
			(at 0 0 90)
			(layer "F.SilkS")
			(hide yes)
			(effects
				(font
					(size 1.27 1.27)
				)
			)
		)
		(property "Value" ""
			(at 0 0 90)
			(layer "F.Fab")
			(effects
				(font
					(size 1.27 1.27)
				)
			)
		)
		(duplicate_pad_numbers_are_jumpers no)
		(fp_line
			(start 0.299974 -0.150114)
			(end 0.299974 0.150114)
			(stroke
				(width 0.1)
				(type default)
			)
			(layer "F.Fab")
		)
		(fp_line
			(start -0.299974 -0.150114)
			(end 0.299974 -0.150114)
			(stroke
				(width 0.1)
				(type default)
			)
			(layer "F.Fab")
		)
		(fp_line
			(start 0.299974 0.150114)
			(end -0.299974 0.150114)
			(stroke
				(width 0.1)
				(type default)
			)
			(layer "F.Fab")
		)
		(fp_line
			(start -0.299974 0.150114)
			(end -0.299974 -0.150114)
			(stroke
				(width 0.1)
				(type default)
			)
			(layer "F.Fab")
		)
		(pad "1" smd rect
			(at -0.2667 0 90)
			(size 0.3048 0.381)
			(layers "F.Cu" "F.Mask" "F.Paste")
			(net "P5E_PEX3_STN4_TX_DN<71>")
		)
		(pad "2" smd rect
			(at 0.2667 0 90)
			(size 0.3048 0.381)
			(layers "F.Cu" "F.Mask" "F.Paste")
			(net "P5E_PEX3_STN4_TX_C_DN<71>")
		)
	)
	(footprint ""
		(layer "F.Cu")
		(at 56.034686 -368.542062 180)
		(property "Reference" "C3985"
			(at 0 0 180)
			(layer "F.SilkS")
			(hide yes)
			(effects
				(font
					(size 1.27 1.27)
				)
			)
		)
		(property "Value" ""
			(at 0 0 180)
			(layer "F.Fab")
			(effects
				(font
					(size 1.27 1.27)
				)
			)
		)
		(duplicate_pad_numbers_are_jumpers no)
		(fp_line
			(start 0.299974 0.150114)
			(end -0.299974 0.150114)
			(stroke
				(width 0.1)
				(type default)
			)
			(layer "F.Fab")
		)
		(fp_line
			(start 0.299974 -0.150114)
			(end 0.299974 0.150114)
			(stroke
				(width 0.1)
				(type default)
			)
			(layer "F.Fab")
		)
		(fp_line
			(start -0.299974 0.150114)
			(end -0.299974 -0.150114)
			(stroke
				(width 0.1)
				(type default)
			)
			(layer "F.Fab")
		)
		(fp_line
			(start -0.299974 -0.150114)
			(end 0.299974 -0.150114)
			(stroke
				(width 0.1)
				(type default)
			)
			(layer "F.Fab")
		)
		(pad "1" smd rect
			(at -0.2667 0 180)
			(size 0.3048 0.381)
			(layers "F.Cu" "F.Mask" "F.Paste")
			(net "P4E_PEX0_STN3_TX_DN<49>")
		)
		(pad "2" smd rect
			(at 0.2667 0 180)
			(size 0.3048 0.381)
			(layers "F.Cu" "F.Mask" "F.Paste")
			(net "P4E_PEX0_STN3_TX_C_DN<49>")
		)
	)
	(footprint ""
		(layer "F.Cu")
		(at 378.841 -190.627)
		(property "Reference" "R4641"
			(at 0 0 0)
			(layer "F.SilkS")
			(hide yes)
			(effects
				(font
					(size 1.27 1.27)
				)
			)
		)
		(property "Value" ""
			(at 0 0 0)
			(layer "F.Fab")
			(effects
				(font
					(size 1.27 1.27)
				)
			)
		)
		(duplicate_pad_numbers_are_jumpers no)
		(fp_line
			(start -0.7874 -0.4064)
			(end 0.7874 -0.4064)
			(stroke
				(width 0.1524)
				(type default)
			)
			(layer "F.SilkS")
		)
		(fp_line
			(start -0.7874 0.4064)
			(end -0.7874 -0.4064)
			(stroke
				(width 0.1524)
				(type default)
			)
			(layer "F.SilkS")
		)
		(fp_line
			(start 0.7874 -0.4064)
			(end 0.7874 0.4064)
			(stroke
				(width 0.1524)
				(type default)
			)
			(layer "F.SilkS")
		)
		(fp_line
			(start 0.7874 0.4064)
			(end -0.7874 0.4064)
			(stroke
				(width 0.1524)
				(type default)
			)
			(layer "F.SilkS")
		)
		(fp_line
			(start -0.67945 -0.305054)
			(end -0.12065 -0.305054)
			(stroke
				(width 0.1)
				(type default)
			)
			(layer "F.Fab")
		)
		(fp_line
			(start -0.67945 0.3048)
			(end -0.67945 -0.305054)
			(stroke
				(width 0.1)
				(type default)
			)
			(layer "F.Fab")
		)
		(fp_line
			(start -0.12065 -0.305054)
			(end -0.12065 -0.2794)
			(stroke
				(width 0.1)
				(type default)
			)
			(layer "F.Fab")
		)
		(fp_line
			(start -0.12065 -0.2794)
			(end 0.12065 -0.2794)
			(stroke
				(width 0.1)
				(type default)
			)
			(layer "F.Fab")
		)
		(fp_line
			(start -0.12065 0.2794)
			(end -0.12065 0.3048)
			(stroke
				(width 0.1)
				(type default)
			)
			(layer "F.Fab")
		)
		(fp_line
			(start -0.12065 0.3048)
			(end -0.67945 0.3048)
			(stroke
				(width 0.1)
				(type default)
			)
			(layer "F.Fab")
		)
		(fp_line
			(start 0.120396 0.2794)
			(end -0.12065 0.2794)
			(stroke
				(width 0.1)
				(type default)
			)
			(layer "F.Fab")
		)
		(fp_line
			(start 0.120396 0.3048)
			(end 0.120396 0.2794)
			(stroke
				(width 0.1)
				(type default)
			)
			(layer "F.Fab")
		)
		(fp_line
			(start 0.12065 -0.3048)
			(end 0.67945 -0.3048)
			(stroke
				(width 0.1)
				(type default)
			)
			(layer "F.Fab")
		)
		(fp_line
			(start 0.12065 -0.2794)
			(end 0.12065 -0.3048)
			(stroke
				(width 0.1)
				(type default)
			)
			(layer "F.Fab")
		)
		(fp_line
			(start 0.67945 -0.3048)
			(end 0.67945 0.3048)
			(stroke
				(width 0.1)
				(type default)
			)
			(layer "F.Fab")
		)
		(fp_line
			(start 0.67945 0.3048)
			(end 0.120396 0.3048)
			(stroke
				(width 0.1)
				(type default)
			)
			(layer "F.Fab")
		)
		(pad "1" smd circle
			(at -0.40005 0)
			(size 0 0)
			(layers "F.Cu" "F.Mask" "F.Paste")
			(net "PCA9555_1_PEX0_A0")
		)
		(pad "2" smd circle
			(at 0.40005 0)
			(size 0 0)
			(layers "F.Cu" "F.Mask" "F.Paste")
			(net "P3V3_AUX")
		)
	)
	(footprint ""
		(layer "F.Cu")
		(at 174.936912 -178.291236 -90)
		(property "Reference" "C4499"
			(at 0 0 270)
			(layer "F.SilkS")
			(hide yes)
			(effects
				(font
					(size 1.27 1.27)
				)
			)
		)
		(property "Value" ""
			(at 0 0 270)
			(layer "F.Fab")
			(effects
				(font
					(size 1.27 1.27)
				)
			)
		)
		(duplicate_pad_numbers_are_jumpers no)
		(fp_line
			(start -0.7874 0.4064)
			(end -0.7874 -0.4064)
			(stroke
				(width 0.1524)
				(type default)
			)
			(layer "F.SilkS")
		)
		(fp_line
			(start 0.7874 0.4064)
			(end -0.7874 0.4064)
			(stroke
				(width 0.1524)
				(type default)
			)
			(layer "F.SilkS")
		)
		(fp_line
			(start -0.7874 -0.4064)
			(end 0.7874 -0.4064)
			(stroke
				(width 0.1524)
				(type default)
			)
			(layer "F.SilkS")
		)
		(fp_line
			(start 0.7874 -0.4064)
			(end 0.7874 0.4064)
			(stroke
				(width 0.1524)
				(type default)
			)
			(layer "F.SilkS")
		)
		(fp_line
			(start -0.67945 0.3048)
			(end -0.67945 -0.305054)
			(stroke
				(width 0.1)
				(type default)
			)
			(layer "F.Fab")
		)
		(fp_line
			(start -0.12065 0.3048)
			(end -0.67945 0.3048)
			(stroke
				(width 0.1)
				(type default)
			)
			(layer "F.Fab")
		)
		(fp_line
			(start 0.120396 0.3048)
			(end 0.120396 0.2794)
			(stroke
				(width 0.1)
				(type default)
			)
			(layer "F.Fab")
		)
		(fp_line
			(start 0.67945 0.3048)
			(end 0.120396 0.3048)
			(stroke
				(width 0.1)
				(type default)
			)
			(layer "F.Fab")
		)
		(fp_line
			(start -0.12065 0.2794)
			(end -0.12065 0.3048)
			(stroke
				(width 0.1)
				(type default)
			)
			(layer "F.Fab")
		)
		(fp_line
			(start 0.120396 0.2794)
			(end -0.12065 0.2794)
			(stroke
				(width 0.1)
				(type default)
			)
			(layer "F.Fab")
		)
		(fp_line
			(start -0.12065 -0.2794)
			(end 0.12065 -0.2794)
			(stroke
				(width 0.1)
				(type default)
			)
			(layer "F.Fab")
		)
		(fp_line
			(start 0.12065 -0.2794)
			(end 0.12065 -0.3048)
			(stroke
				(width 0.1)
				(type default)
			)
			(layer "F.Fab")
		)
		(fp_line
			(start 0.12065 -0.3048)
			(end 0.67945 -0.3048)
			(stroke
				(width 0.1)
				(type default)
			)
			(layer "F.Fab")
		)
		(fp_line
			(start 0.67945 -0.3048)
			(end 0.67945 0.3048)
			(stroke
				(width 0.1)
				(type default)
			)
			(layer "F.Fab")
		)
		(fp_line
			(start -0.67945 -0.305054)
			(end -0.12065 -0.305054)
			(stroke
				(width 0.1)
				(type default)
			)
			(layer "F.Fab")
		)
		(fp_line
			(start -0.12065 -0.305054)
			(end -0.12065 -0.2794)
			(stroke
				(width 0.1)
				(type default)
			)
			(layer "F.Fab")
		)
		(pad "1" smd circle
			(at -0.40005 0 270)
			(size 0 0)
			(layers "F.Cu" "F.Mask" "F.Paste")
			(net "NIC2_CLK_EN_R_N")
		)
		(pad "2" smd circle
			(at 0.40005 0 270)
			(size 0 0)
			(layers "F.Cu" "F.Mask" "F.Paste")
			(net "GND")
		)
	)
)
